# T6G (Grand Teton) — schematic netlist excerpt (pin names and nets, part order shuffled) for the footprints in the layout excerpt that follows; sources: Cadence DE-HDL packaged netlist, KiCad conversion of 04192023_DAF0TMB3IC0_F0TG_MB_C_brd_V02_OCP.brd

R772  Q_RES  35.7K 1% CHIP  pkg 0402LF  page 101 : A = PD_CHD_CPU1_DIMM_SAA ; B = GND
R6131  Q_RES  1K 1% EMPTY  pkg 0402LF  page 84 : A = PVDD18_S5_P0 ; B = FAB_REV_ID1

(kicad_pcb
	(version 20260206)
	(generator "pcbnew")
	(generator_version "10.0")
	(general
		(thickness 1.6)
		(legacy_teardrops no)
	)
	(paper "A4")
	(title_block
		(title "04192023_DAF0TMB3IC0_F0TG_MB_C_brd_V02_OCP.brd")
		(comment 1 "Grand Teton / footprints 6653-6654 of 8354")
	)
	(layers
		(0 "F.Cu" signal "TOP")
		(4 "In1.Cu" signal "GND")
		(6 "In2.Cu" signal "IN1")
		(8 "In3.Cu" signal "GND1")
		(10 "In4.Cu" signal "IN2")
		(12 "In5.Cu" signal "GND2")
		(14 "In6.Cu" signal "IN3")
		(16 "In7.Cu" signal "GND3")
		(18 "In8.Cu" signal "VCC")
		(20 "In9.Cu" signal "VCC1")
		(22 "In10.Cu" signal "GND4")
		(24 "In11.Cu" signal "IN4")
		(26 "In12.Cu" signal "GND5")
		(28 "In13.Cu" signal "IN5")
		(30 "In14.Cu" signal "GND6")
		(32 "In15.Cu" signal "IN6")
		(34 "In16.Cu" signal "GND7")
		(2 "B.Cu" signal "BOTTOM")
		(9 "F.Adhes" user "F.Adhesive")
		(11 "B.Adhes" user "B.Adhesive")
		(13 "F.Paste" user "Package Geometry/Pastemask Top")
		(15 "B.Paste" user "Package Geometry/Pastemask Bottom")
		(5 "F.SilkS" user "Ref Des/Silkscreen Top")
		(7 "B.SilkS" user "Ref Des/Silkscreen Bottom")
		(1 "F.Mask" user "Board Geometry/Soldermask Top")
		(3 "B.Mask" user "Board Geometry/Soldermask Bottom")
		(17 "Dwgs.User" user "User.Drawings")
		(19 "Cmts.User" user "User.Comments")
		(21 "Eco1.User" user "User.Eco1")
		(23 "Eco2.User" user "User.Eco2")
		(25 "Edge.Cuts" user "Board Geometry/Outline")
		(27 "Margin" user)
		(31 "F.CrtYd" user "Package Geometry/Place Bound Top")
		(29 "B.CrtYd" user "Package Geometry/Place Bound Bottom")
		(35 "F.Fab" user "Ref Des/Assembly Top")
		(33 "B.Fab" user "Ref Des/Assembly Bottom")
	)
	(footprint ""
		(layer "B.Cu")
		(at 396.218918 -203.879958 -90)
		(property "Reference" "R6131"
			(at 0 0 90)
			(layer "B.SilkS")
			(hide yes)
			(effects
				(font
					(size 1.27 1.27)
				)
				(justify mirror)
			)
		)
		(property "Value" ""
			(at 0 0 90)
			(layer "B.Fab")
			(effects
				(font
					(size 1.27 1.27)
				)
				(justify mirror)
			)
		)
		(duplicate_pad_numbers_are_jumpers no)
		(fp_line
			(start -0.7874 0.4064)
			(end 0.7874 0.4064)
			(stroke
				(width 0.1524)
				(type default)
			)
			(layer "B.SilkS")
		)
		(fp_line
			(start 0.7874 0.4064)
			(end 0.7874 -0.4064)
			(stroke
				(width 0.1524)
				(type default)
			)
			(layer "B.SilkS")
		)
		(fp_line
			(start -0.7874 -0.4064)
			(end -0.7874 0.4064)
			(stroke
				(width 0.1524)
				(type default)
			)
			(layer "B.SilkS")
		)
		(fp_line
			(start 0.7874 -0.4064)
			(end -0.7874 -0.4064)
			(stroke
				(width 0.1524)
				(type default)
			)
			(layer "B.SilkS")
		)
		(fp_line
			(start -0.67945 0.3048)
			(end -0.120396 0.3048)
			(stroke
				(width 0.1)
				(type default)
			)
			(layer "B.Fab")
		)
		(fp_line
			(start -0.120396 0.3048)
			(end -0.120396 0.2794)
			(stroke
				(width 0.1)
				(type default)
			)
			(layer "B.Fab")
		)
		(fp_line
			(start 0.12065 0.3048)
			(end 0.67945 0.3048)
			(stroke
				(width 0.1)
				(type default)
			)
			(layer "B.Fab")
		)
		(fp_line
			(start 0.67945 0.3048)
			(end 0.67945 -0.305054)
			(stroke
				(width 0.1)
				(type default)
			)
			(layer "B.Fab")
		)
		(fp_line
			(start -0.120396 0.2794)
			(end 0.12065 0.2794)
			(stroke
				(width 0.1)
				(type default)
			)
			(layer "B.Fab")
		)
		(fp_line
			(start 0.12065 0.2794)
			(end 0.12065 0.3048)
			(stroke
				(width 0.1)
				(type default)
			)
			(layer "B.Fab")
		)
		(fp_line
			(start -0.12065 -0.2794)
			(end -0.12065 -0.3048)
			(stroke
				(width 0.1)
				(type default)
			)
			(layer "B.Fab")
		)
		(fp_line
			(start 0.12065 -0.2794)
			(end -0.12065 -0.2794)
			(stroke
				(width 0.1)
				(type default)
			)
			(layer "B.Fab")
		)
		(fp_line
			(start -0.67945 -0.3048)
			(end -0.67945 0.3048)
			(stroke
				(width 0.1)
				(type default)
			)
			(layer "B.Fab")
		)
		(fp_line
			(start -0.12065 -0.3048)
			(end -0.67945 -0.3048)
			(stroke
				(width 0.1)
				(type default)
			)
			(layer "B.Fab")
		)
		(fp_line
			(start 0.12065 -0.305054)
			(end 0.12065 -0.2794)
			(stroke
				(width 0.1)
				(type default)
			)
			(layer "B.Fab")
		)
		(fp_line
			(start 0.67945 -0.305054)
			(end 0.12065 -0.305054)
			(stroke
				(width 0.1)
				(type default)
			)
			(layer "B.Fab")
		)
		(pad "1" smd circle
			(at 0.40005 0 90)
			(size 0 0)
			(layers "B.Cu" "B.Mask" "B.Paste")
			(net "PVDD18_S5_P0")
		)
		(pad "2" smd circle
			(at -0.40005 0 90)
			(size 0 0)
			(layers "B.Cu" "B.Mask" "B.Paste")
			(net "FAB_REV_ID1")
		)
	)
	(footprint ""
		(layer "B.Cu")
		(at 33.467294 -194.885564 180)
		(property "Reference" "R772"
			(at 0 0 0)
			(layer "B.SilkS")
			(hide yes)
			(effects
				(font
					(size 1.27 1.27)
				)
				(justify mirror)
			)
		)
		(property "Value" ""
			(at 0 0 0)
			(layer "B.Fab")
			(effects
				(font
					(size 1.27 1.27)
				)
				(justify mirror)
			)
		)
		(duplicate_pad_numbers_are_jumpers no)
		(fp_line
			(start 0.7874 0.4064)
			(end 0.7874 -0.4064)
			(stroke
				(width 0.1524)
				(type default)
			)
			(layer "B.SilkS")
		)
		(fp_line
			(start 0.7874 -0.4064)
			(end -0.7874 -0.4064)
			(stroke
				(width 0.1524)
				(type default)
			)
			(layer "B.SilkS")
		)
		(fp_line
			(start -0.7874 0.4064)
			(end 0.7874 0.4064)
			(stroke
				(width 0.1524)
				(type default)
			)
			(layer "B.SilkS")
		)
		(fp_line
			(start -0.7874 -0.4064)
			(end -0.7874 0.4064)
			(stroke
				(width 0.1524)
				(type default)
			)
			(layer "B.SilkS")
		)
		(fp_line
			(start 0.67945 0.3048)
			(end 0.67945 -0.305054)
			(stroke
				(width 0.1)
				(type default)
			)
			(layer "B.Fab")
		)
		(fp_line
			(start 0.67945 -0.305054)
			(end 0.12065 -0.305054)
			(stroke
				(width 0.1)
				(type default)
			)
			(layer "B.Fab")
		)
		(fp_line
			(start 0.12065 0.3048)
			(end 0.67945 0.3048)
			(stroke
				(width 0.1)
				(type default)
			)
			(layer "B.Fab")
		)
		(fp_line
			(start 0.12065 0.2794)
			(end 0.12065 0.3048)
			(stroke
				(width 0.1)
				(type default)
			)
			(layer "B.Fab")
		)
		(fp_line
			(start 0.12065 -0.2794)
			(end -0.12065 -0.2794)
			(stroke
				(width 0.1)
				(type default)
			)
			(layer "B.Fab")
		)
		(fp_line
			(start 0.12065 -0.305054)
			(end 0.12065 -0.2794)
			(stroke
				(width 0.1)
				(type default)
			)
			(layer "B.Fab")
		)
		(fp_line
			(start -0.120396 0.3048)
			(end -0.120396 0.2794)
			(stroke
				(width 0.1)
				(type default)
			)
			(layer "B.Fab")
		)
		(fp_line
			(start -0.120396 0.2794)
			(end 0.12065 0.2794)
			(stroke
				(width 0.1)
				(type default)
			)
			(layer "B.Fab")
		)
		(fp_line
			(start -0.12065 -0.2794)
			(end -0.12065 -0.3048)
			(stroke
				(width 0.1)
				(type default)
			)
			(layer "B.Fab")
		)
		(fp_line
			(start -0.12065 -0.3048)
			(end -0.67945 -0.3048)
			(stroke
				(width 0.1)
				(type default)
			)
			(layer "B.Fab")
		)
		(fp_line
			(start -0.67945 0.3048)
			(end -0.120396 0.3048)
			(stroke
				(width 0.1)
				(type default)
			)
			(layer "B.Fab")
		)
		(fp_line
			(start -0.67945 -0.3048)
			(end -0.67945 0.3048)
			(stroke
				(width 0.1)
				(type default)
			)
			(layer "B.Fab")
		)
		(pad "1" smd circle
			(at 0.40005 0)
			(size 0 0)
			(layers "B.Cu" "B.Mask" "B.Paste")
			(net "PD_CHD_CPU1_DIMM_SAA")
		)
		(pad "2" smd circle
			(at -0.40005 0)
			(size 0 0)
			(layers "B.Cu" "B.Mask" "B.Paste")
			(net "GND")
		)
	)
)
